(kicad_pcb
	(version 20260206)
	(generator "pcbnew")
	(generator_version "10.0")
	(general
		(thickness 1.6)
		(legacy_teardrops no)
	)
	(paper "A4")
	(title_block
		(title "04192023_DAF0TMB3IC0_F0TG_MB_C_brd_V02_OCP.brd")
		(comment 1 "Grand Teton / footprints 7875-7880 of 8354")
	)
	(layers
		(0 "F.Cu" signal "TOP")
		(4 "In1.Cu" signal "GND")
		(6 "In2.Cu" signal "IN1")
		(8 "In3.Cu" signal "GND1")
		(10 "In4.Cu" signal "IN2")
		(12 "In5.Cu" signal "GND2")
		(14 "In6.Cu" signal "IN3")
		(16 "In7.Cu" signal "GND3")
		(18 "In8.Cu" signal "VCC")
		(20 "In9.Cu" signal "VCC1")
		(22 "In10.Cu" signal "GND4")
		(24 "In11.Cu" signal "IN4")
		(26 "In12.Cu" signal "GND5")
		(28 "In13.Cu" signal "IN5")
		(30 "In14.Cu" signal "GND6")
		(32 "In15.Cu" signal "IN6")
		(34 "In16.Cu" signal "GND7")
		(2 "B.Cu" signal "BOTTOM")
		(9 "F.Adhes" user "F.Adhesive")
		(11 "B.Adhes" user "B.Adhesive")
		(13 "F.Paste" user "Package Geometry/Pastemask Top")
		(15 "B.Paste" user "Package Geometry/Pastemask Bottom")
		(5 "F.SilkS" user "Ref Des/Silkscreen Top")
		(7 "B.SilkS" user "Ref Des/Silkscreen Bottom")
		(1 "F.Mask" user "Board Geometry/Soldermask Top")
		(3 "B.Mask" user "Board Geometry/Soldermask Bottom")
		(17 "Dwgs.User" user "User.Drawings")
		(19 "Cmts.User" user "User.Comments")
		(21 "Eco1.User" user "User.Eco1")
		(23 "Eco2.User" user "User.Eco2")
		(25 "Edge.Cuts" user "Board Geometry/Outline")
		(27 "Margin" user)
		(31 "F.CrtYd" user "Package Geometry/Place Bound Top")
		(29 "B.CrtYd" user "Package Geometry/Place Bound Bottom")
		(35 "F.Fab" user "Ref Des/Assembly Top")
		(33 "B.Fab" user "Ref Des/Assembly Bottom")
	)
	(footprint ""
		(layer "B.Cu")
		(at 115.610386 -253.432564)
		(property "Reference" "C2426"
			(at 0 0 0)
			(layer "B.SilkS")
			(hide yes)
			(effects
				(font
					(size 1.27 1.27)
				)
				(justify mirror)
			)
		)
		(property "Value" ""
			(at 0 0 0)
			(layer "B.Fab")
			(effects
				(font
					(size 1.27 1.27)
				)
				(justify mirror)
			)
		)
		(duplicate_pad_numbers_are_jumpers no)
		(fp_line
			(start -0.7874 -0.4064)
			(end -0.7874 0.4064)
			(stroke
				(width 0.1524)
				(type default)
			)
			(layer "B.SilkS")
		)
		(fp_line
			(start -0.7874 0.4064)
			(end 0.7874 0.4064)
			(stroke
				(width 0.1524)
				(type default)
			)
			(layer "B.SilkS")
		)
		(fp_line
			(start 0.7874 -0.4064)
			(end -0.7874 -0.4064)
			(stroke
				(width 0.1524)
				(type default)
			)
			(layer "B.SilkS")
		)
		(fp_line
			(start 0.7874 0.4064)
			(end 0.7874 -0.4064)
			(stroke
				(width 0.1524)
				(type default)
			)
			(layer "B.SilkS")
		)
		(fp_line
			(start -0.67945 -0.3048)
			(end -0.67945 0.3048)
			(stroke
				(width 0.1)
				(type default)
			)
			(layer "B.Fab")
		)
		(fp_line
			(start -0.67945 0.3048)
			(end -0.120396 0.3048)
			(stroke
				(width 0.1)
				(type default)
			)
			(layer "B.Fab")
		)
		(fp_line
			(start -0.12065 -0.3048)
			(end -0.67945 -0.3048)
			(stroke
				(width 0.1)
				(type default)
			)
			(layer "B.Fab")
		)
		(fp_line
			(start -0.12065 -0.2794)
			(end -0.12065 -0.3048)
			(stroke
				(width 0.1)
				(type default)
			)
			(layer "B.Fab")
		)
		(fp_line
			(start -0.120396 0.2794)
			(end 0.12065 0.2794)
			(stroke
				(width 0.1)
				(type default)
			)
			(layer "B.Fab")
		)
		(fp_line
			(start -0.120396 0.3048)
			(end -0.120396 0.2794)
			(stroke
				(width 0.1)
				(type default)
			)
			(layer "B.Fab")
		)
		(fp_line
			(start 0.12065 -0.305054)
			(end 0.12065 -0.2794)
			(stroke
				(width 0.1)
				(type default)
			)
			(layer "B.Fab")
		)
		(fp_line
			(start 0.12065 -0.2794)
			(end -0.12065 -0.2794)
			(stroke
				(width 0.1)
				(type default)
			)
			(layer "B.Fab")
		)
		(fp_line
			(start 0.12065 0.2794)
			(end 0.12065 0.3048)
			(stroke
				(width 0.1)
				(type default)
			)
			(layer "B.Fab")
		)
		(fp_line
			(start 0.12065 0.3048)
			(end 0.67945 0.3048)
			(stroke
				(width 0.1)
				(type default)
			)
			(layer "B.Fab")
		)
		(fp_line
			(start 0.67945 -0.305054)
			(end 0.12065 -0.305054)
			(stroke
				(width 0.1)
				(type default)
			)
			(layer "B.Fab")
		)
		(fp_line
			(start 0.67945 0.3048)
			(end 0.67945 -0.305054)
			(stroke
				(width 0.1)
				(type default)
			)
			(layer "B.Fab")
		)
		(pad "1" smd circle
			(at 0.40005 0 180)
			(size 0 0)
			(layers "B.Cu" "B.Mask" "B.Paste")
			(net "PVDDCR_SOC_P1")
		)
		(pad "2" smd circle
			(at -0.40005 0 180)
			(size 0 0)
			(layers "B.Cu" "B.Mask" "B.Paste")
			(net "GND")
		)
	)
	(footprint ""
		(layer "B.Cu")
		(at 193.6369 -402.033232 -90)
		(property "Reference" "PR3910"
			(at 0 0 90)
			(layer "B.SilkS")
			(hide yes)
			(effects
				(font
					(size 1.27 1.27)
				)
				(justify mirror)
			)
		)
		(property "Value" ""
			(at 0 0 90)
			(layer "B.Fab")
			(effects
				(font
					(size 1.27 1.27)
				)
				(justify mirror)
			)
		)
		(duplicate_pad_numbers_are_jumpers no)
		(fp_line
			(start -0.7874 0.4064)
			(end 0.7874 0.4064)
			(stroke
				(width 0.1524)
				(type default)
			)
			(layer "B.SilkS")
		)
		(fp_line
			(start 0.7874 0.4064)
			(end 0.7874 -0.4064)
			(stroke
				(width 0.1524)
				(type default)
			)
			(layer "B.SilkS")
		)
		(fp_line
			(start -0.7874 -0.4064)
			(end -0.7874 0.4064)
			(stroke
				(width 0.1524)
				(type default)
			)
			(layer "B.SilkS")
		)
		(fp_line
			(start 0.7874 -0.4064)
			(end -0.7874 -0.4064)
			(stroke
				(width 0.1524)
				(type default)
			)
			(layer "B.SilkS")
		)
		(fp_line
			(start -0.67945 0.3048)
			(end -0.120396 0.3048)
			(stroke
				(width 0.1)
				(type default)
			)
			(layer "B.Fab")
		)
		(fp_line
			(start -0.120396 0.3048)
			(end -0.120396 0.2794)
			(stroke
				(width 0.1)
				(type default)
			)
			(layer "B.Fab")
		)
		(fp_line
			(start 0.12065 0.3048)
			(end 0.67945 0.3048)
			(stroke
				(width 0.1)
				(type default)
			)
			(layer "B.Fab")
		)
		(fp_line
			(start 0.67945 0.3048)
			(end 0.67945 -0.305054)
			(stroke
				(width 0.1)
				(type default)
			)
			(layer "B.Fab")
		)
		(fp_line
			(start -0.120396 0.2794)
			(end 0.12065 0.2794)
			(stroke
				(width 0.1)
				(type default)
			)
			(layer "B.Fab")
		)
		(fp_line
			(start 0.12065 0.2794)
			(end 0.12065 0.3048)
			(stroke
				(width 0.1)
				(type default)
			)
			(layer "B.Fab")
		)
		(fp_line
			(start -0.12065 -0.2794)
			(end -0.12065 -0.3048)
			(stroke
				(width 0.1)
				(type default)
			)
			(layer "B.Fab")
		)
		(fp_line
			(start 0.12065 -0.2794)
			(end -0.12065 -0.2794)
			(stroke
				(width 0.1)
				(type default)
			)
			(layer "B.Fab")
		)
		(fp_line
			(start -0.67945 -0.3048)
			(end -0.67945 0.3048)
			(stroke
				(width 0.1)
				(type default)
			)
			(layer "B.Fab")
		)
		(fp_line
			(start -0.12065 -0.3048)
			(end -0.67945 -0.3048)
			(stroke
				(width 0.1)
				(type default)
			)
			(layer "B.Fab")
		)
		(fp_line
			(start 0.12065 -0.305054)
			(end 0.12065 -0.2794)
			(stroke
				(width 0.1)
				(type default)
			)
			(layer "B.Fab")
		)
		(fp_line
			(start 0.67945 -0.305054)
			(end 0.12065 -0.305054)
			(stroke
				(width 0.1)
				(type default)
			)
			(layer "B.Fab")
		)
		(pad "1" smd circle
			(at 0.40005 0 90)
			(size 0 0)
			(layers "B.Cu" "B.Mask" "B.Paste")
			(net "HSC_VDD_R_1")
		)
		(pad "2" smd circle
			(at -0.40005 0 90)
			(size 0 0)
			(layers "B.Cu" "B.Mask" "B.Paste")
			(net "HSC_VDD")
		)
	)
	(footprint ""
		(layer "B.Cu")
		(at 16.610838 -97.314512 90)
		(property "Reference" "C2039"
			(at 0 0 90)
			(layer "B.SilkS")
			(hide yes)
			(effects
				(font
					(size 1.27 1.27)
				)
				(justify mirror)
			)
		)
		(property "Value" ""
			(at 0 0 90)
			(layer "B.Fab")
			(effects
				(font
					(size 1.27 1.27)
				)
				(justify mirror)
			)
		)
		(duplicate_pad_numbers_are_jumpers no)
		(fp_line
			(start 0.7874 -0.4064)
			(end -0.7874 -0.4064)
			(stroke
				(width 0.1524)
				(type default)
			)
			(layer "B.SilkS")
		)
		(fp_line
			(start -0.7874 -0.4064)
			(end -0.7874 0.4064)
			(stroke
				(width 0.1524)
				(type default)
			)
			(layer "B.SilkS")
		)
		(fp_line
			(start 0.7874 0.4064)
			(end 0.7874 -0.4064)
			(stroke
				(width 0.1524)
				(type default)
			)
			(layer "B.SilkS")
		)
		(fp_line
			(start -0.7874 0.4064)
			(end 0.7874 0.4064)
			(stroke
				(width 0.1524)
				(type default)
			)
			(layer "B.SilkS")
		)
		(fp_line
			(start 0.67945 -0.305054)
			(end 0.12065 -0.305054)
			(stroke
				(width 0.1)
				(type default)
			)
			(layer "B.Fab")
		)
		(fp_line
			(start 0.12065 -0.305054)
			(end 0.12065 -0.2794)
			(stroke
				(width 0.1)
				(type default)
			)
			(layer "B.Fab")
		)
		(fp_line
			(start -0.12065 -0.3048)
			(end -0.67945 -0.3048)
			(stroke
				(width 0.1)
				(type default)
			)
			(layer "B.Fab")
		)
		(fp_line
			(start -0.67945 -0.3048)
			(end -0.67945 0.3048)
			(stroke
				(width 0.1)
				(type default)
			)
			(layer "B.Fab")
		)
		(fp_line
			(start 0.12065 -0.2794)
			(end -0.12065 -0.2794)
			(stroke
				(width 0.1)
				(type default)
			)
			(layer "B.Fab")
		)
		(fp_line
			(start -0.12065 -0.2794)
			(end -0.12065 -0.3048)
			(stroke
				(width 0.1)
				(type default)
			)
			(layer "B.Fab")
		)
		(fp_line
			(start 0.12065 0.2794)
			(end 0.12065 0.3048)
			(stroke
				(width 0.1)
				(type default)
			)
			(layer "B.Fab")
		)
		(fp_line
			(start -0.120396 0.2794)
			(end 0.12065 0.2794)
			(stroke
				(width 0.1)
				(type default)
			)
			(layer "B.Fab")
		)
		(fp_line
			(start 0.67945 0.3048)
			(end 0.67945 -0.305054)
			(stroke
				(width 0.1)
				(type default)
			)
			(layer "B.Fab")
		)
		(fp_line
			(start 0.12065 0.3048)
			(end 0.67945 0.3048)
			(stroke
				(width 0.1)
				(type default)
			)
			(layer "B.Fab")
		)
		(fp_line
			(start -0.120396 0.3048)
			(end -0.120396 0.2794)
			(stroke
				(width 0.1)
				(type default)
			)
			(layer "B.Fab")
		)
		(fp_line
			(start -0.67945 0.3048)
			(end -0.120396 0.3048)
			(stroke
				(width 0.1)
				(type default)
			)
			(layer "B.Fab")
		)
		(pad "1" smd circle
			(at 0.40005 0 270)
			(size 0 0)
			(layers "B.Cu" "B.Mask" "B.Paste")
			(net "P3V3_AUX_USB_HUB")
		)
		(pad "2" smd circle
			(at -0.40005 0 270)
			(size 0 0)
			(layers "B.Cu" "B.Mask" "B.Paste")
			(net "GND")
		)
	)
	(footprint ""
		(layer "B.Cu")
		(at 399.057622 -204.232002)
		(property "Reference" "C30"
			(at 0 0 0)
			(layer "B.SilkS")
			(hide yes)
			(effects
				(font
					(size 1.27 1.27)
				)
				(justify mirror)
			)
		)
		(property "Value" ""
			(at 0 0 0)
			(layer "B.Fab")
			(effects
				(font
					(size 1.27 1.27)
				)
				(justify mirror)
			)
		)
		(duplicate_pad_numbers_are_jumpers no)
		(fp_line
			(start -0.7874 -0.4064)
			(end -0.7874 0.4064)
			(stroke
				(width 0.1524)
				(type default)
			)
			(layer "B.SilkS")
		)
		(fp_line
			(start -0.7874 0.4064)
			(end 0.7874 0.4064)
			(stroke
				(width 0.1524)
				(type default)
			)
			(layer "B.SilkS")
		)
		(fp_line
			(start 0.7874 -0.4064)
			(end -0.7874 -0.4064)
			(stroke
				(width 0.1524)
				(type default)
			)
			(layer "B.SilkS")
		)
		(fp_line
			(start 0.7874 0.4064)
			(end 0.7874 -0.4064)
			(stroke
				(width 0.1524)
				(type default)
			)
			(layer "B.SilkS")
		)
		(fp_line
			(start -0.67945 -0.3048)
			(end -0.67945 0.3048)
			(stroke
				(width 0.1)
				(type default)
			)
			(layer "B.Fab")
		)
		(fp_line
			(start -0.67945 0.3048)
			(end -0.120396 0.3048)
			(stroke
				(width 0.1)
				(type default)
			)
			(layer "B.Fab")
		)
		(fp_line
			(start -0.12065 -0.3048)
			(end -0.67945 -0.3048)
			(stroke
				(width 0.1)
				(type default)
			)
			(layer "B.Fab")
		)
		(fp_line
			(start -0.12065 -0.2794)
			(end -0.12065 -0.3048)
			(stroke
				(width 0.1)
				(type default)
			)
			(layer "B.Fab")
		)
		(fp_line
			(start -0.120396 0.2794)
			(end 0.12065 0.2794)
			(stroke
				(width 0.1)
				(type default)
			)
			(layer "B.Fab")
		)
		(fp_line
			(start -0.120396 0.3048)
			(end -0.120396 0.2794)
			(stroke
				(width 0.1)
				(type default)
			)
			(layer "B.Fab")
		)
		(fp_line
			(start 0.12065 -0.305054)
			(end 0.12065 -0.2794)
			(stroke
				(width 0.1)
				(type default)
			)
			(layer "B.Fab")
		)
		(fp_line
			(start 0.12065 -0.2794)
			(end -0.12065 -0.2794)
			(stroke
				(width 0.1)
				(type default)
			)
			(layer "B.Fab")
		)
		(fp_line
			(start 0.12065 0.2794)
			(end 0.12065 0.3048)
			(stroke
				(width 0.1)
				(type default)
			)
			(layer "B.Fab")
		)
		(fp_line
			(start 0.12065 0.3048)
			(end 0.67945 0.3048)
			(stroke
				(width 0.1)
				(type default)
			)
			(layer "B.Fab")
		)
		(fp_line
			(start 0.67945 -0.305054)
			(end 0.12065 -0.305054)
			(stroke
				(width 0.1)
				(type default)
			)
			(layer "B.Fab")
		)
		(fp_line
			(start 0.67945 0.3048)
			(end 0.67945 -0.305054)
			(stroke
				(width 0.1)
				(type default)
			)
			(layer "B.Fab")
		)
		(pad "1" smd circle
			(at 0.40005 0 180)
			(size 0 0)
			(layers "B.Cu" "B.Mask" "B.Paste")
			(net "P1V8_AUX")
		)
		(pad "2" smd circle
			(at -0.40005 0 180)
			(size 0 0)
			(layers "B.Cu" "B.Mask" "B.Paste")
			(net "GND")
		)
	)
	(footprint ""
		(layer "B.Cu")
		(at 349.118682 -398.942052 90)
		(property "Reference" "C644"
			(at 0 0 90)
			(layer "B.SilkS")
			(hide yes)
			(effects
				(font
					(size 1.27 1.27)
				)
				(justify mirror)
			)
		)
		(property "Value" ""
			(at 0 0 90)
			(layer "B.Fab")
			(effects
				(font
					(size 1.27 1.27)
				)
				(justify mirror)
			)
		)
		(duplicate_pad_numbers_are_jumpers no)
		(fp_line
			(start 0.7874 -0.4064)
			(end -0.7874 -0.4064)
			(stroke
				(width 0.1524)
				(type default)
			)
			(layer "B.SilkS")
		)
		(fp_line
			(start -0.7874 -0.4064)
			(end -0.7874 0.4064)
			(stroke
				(width 0.1524)
				(type default)
			)
			(layer "B.SilkS")
		)
		(fp_line
			(start 0.7874 0.4064)
			(end 0.7874 -0.4064)
			(stroke
				(width 0.1524)
				(type default)
			)
			(layer "B.SilkS")
		)
		(fp_line
			(start -0.7874 0.4064)
			(end 0.7874 0.4064)
			(stroke
				(width 0.1524)
				(type default)
			)
			(layer "B.SilkS")
		)
		(fp_line
			(start 0.67945 -0.305054)
			(end 0.12065 -0.305054)
			(stroke
				(width 0.1)
				(type default)
			)
			(layer "B.Fab")
		)
		(fp_line
			(start 0.12065 -0.305054)
			(end 0.12065 -0.2794)
			(stroke
				(width 0.1)
				(type default)
			)
			(layer "B.Fab")
		)
		(fp_line
			(start -0.12065 -0.3048)
			(end -0.67945 -0.3048)
			(stroke
				(width 0.1)
				(type default)
			)
			(layer "B.Fab")
		)
		(fp_line
			(start -0.67945 -0.3048)
			(end -0.67945 0.3048)
			(stroke
				(width 0.1)
				(type default)
			)
			(layer "B.Fab")
		)
		(fp_line
			(start 0.12065 -0.2794)
			(end -0.12065 -0.2794)
			(stroke
				(width 0.1)
				(type default)
			)
			(layer "B.Fab")
		)
		(fp_line
			(start -0.12065 -0.2794)
			(end -0.12065 -0.3048)
			(stroke
				(width 0.1)
				(type default)
			)
			(layer "B.Fab")
		)
		(fp_line
			(start 0.12065 0.2794)
			(end 0.12065 0.3048)
			(stroke
				(width 0.1)
				(type default)
			)
			(layer "B.Fab")
		)
		(fp_line
			(start -0.120396 0.2794)
			(end 0.12065 0.2794)
			(stroke
				(width 0.1)
				(type default)
			)
			(layer "B.Fab")
		)
		(fp_line
			(start 0.67945 0.3048)
			(end 0.67945 -0.305054)
			(stroke
				(width 0.1)
				(type default)
			)
			(layer "B.Fab")
		)
		(fp_line
			(start 0.12065 0.3048)
			(end 0.67945 0.3048)
			(stroke
				(width 0.1)
				(type default)
			)
			(layer "B.Fab")
		)
		(fp_line
			(start -0.120396 0.3048)
			(end -0.120396 0.2794)
			(stroke
				(width 0.1)
				(type default)
			)
			(layer "B.Fab")
		)
		(fp_line
			(start -0.67945 0.3048)
			(end -0.120396 0.3048)
			(stroke
				(width 0.1)
				(type default)
			)
			(layer "B.Fab")
		)
		(pad "1" smd circle
			(at 0.40005 0 270)
			(size 0 0)
			(layers "B.Cu" "B.Mask" "B.Paste")
			(net "P0V9_CPU0_RT1_2A")
		)
		(pad "2" smd circle
			(at -0.40005 0 270)
			(size 0 0)
			(layers "B.Cu" "B.Mask" "B.Paste")
			(net "GND")
		)
	)
	(footprint ""
		(layer "B.Cu")
		(at 188.712094 -113.862866)
		(property "Reference" "C356"
			(at 0 0 0)
			(layer "B.SilkS")
			(hide yes)
			(effects
				(font
					(size 1.27 1.27)
				)
				(justify mirror)
			)
		)
		(property "Value" ""
			(at 0 0 0)
			(layer "B.Fab")
			(effects
				(font
					(size 1.27 1.27)
				)
				(justify mirror)
			)
		)
		(duplicate_pad_numbers_are_jumpers no)
		(fp_line
			(start -0.69215 -0.2921)
			(end -0.69215 0.2921)
			(stroke
				(width 0.1524)
				(type default)
			)
			(layer "B.SilkS")
		)
		(fp_line
			(start -0.69215 0.2921)
			(end 0.69215 0.2921)
			(stroke
				(width 0.1524)
				(type default)
			)
			(layer "B.SilkS")
		)
		(fp_line
			(start 0.69215 -0.2921)
			(end -0.69215 -0.2921)
			(stroke
				(width 0.1524)
				(type default)
			)
			(layer "B.SilkS")
		)
		(fp_line
			(start 0.69215 0.2921)
			(end 0.69215 -0.2921)
			(stroke
				(width 0.1524)
				(type default)
			)
			(layer "B.SilkS")
		)
		(fp_line
			(start -0.51435 -0.2794)
			(end -0.51435 0.2794)
			(stroke
				(width 0.1)
				(type default)
			)
			(layer "B.Fab")
		)
		(fp_line
			(start -0.51435 0.2794)
			(end 0.51435 0.2794)
			(stroke
				(width 0.1)
				(type default)
			)
			(layer "B.Fab")
		)
		(fp_line
			(start 0.51435 -0.2794)
			(end -0.51435 -0.2794)
			(stroke
				(width 0.1)
				(type default)
			)
			(layer "B.Fab")
		)
		(fp_line
			(start 0.51435 0.2794)
			(end 0.51435 -0.2794)
			(stroke
				(width 0.1)
				(type default)
			)
			(layer "B.Fab")
		)
		(pad "1" smd circle
			(at 0.40005 0 180)
			(size 0 0)
			(layers "B.Cu" "B.Mask" "B.Paste")
			(net "P3V3_AUX")
		)
		(pad "2" smd circle
			(at -0.40005 0 180)
			(size 0 0)
			(layers "B.Cu" "B.Mask" "B.Paste")
			(net "GND")
		)
		(zone
			(layer "B.Cu")
			(hatch none 0.5)
			(connect_pads
				(clearance 0)
			)
			(min_thickness 0.25)
			(keepout
				(tracks not_allowed)
				(vias allowed)
				(pads allowed)
				(copperpour not_allowed)
				(footprints allowed)
			)
			(placement
				(enabled no)
				(sheetname "")
			)
			(fill
				(thermal_gap 0.5)
				(thermal_bridge_width 0.5)
				(island_removal_mode 0)
			)
			(polygon
				(pts
					(xy 188.521594 -113.775236) (xy 188.521594 -113.950496) (xy 188.611764 -114.008916) (xy 188.811154 -114.008916)
					(xy 188.902594 -113.95075) (xy 188.902594 -113.775236) (xy 188.811154 -113.71707) (xy 188.611764 -113.71707)
				)
			)
		)
	)
)
